(kicad_pcb
	(version 20260206)
	(generator "pcbnew")
	(generator_version "10.0")
	(general
		(thickness 1.6)
		(legacy_teardrops no)
	)
	(paper "A4")
	(title_block
		(title "03242023_DA0F0TMBIJ0_F0T_Motherboard_J_brd_V01_OCP.brd")
		(comment 1 "Grand Teton / footprints 322-327 of 6105")
	)
	(layers
		(0 "F.Cu" signal "TOP")
		(4 "In1.Cu" signal "GND")
		(6 "In2.Cu" signal "IN1")
		(8 "In3.Cu" signal "GND1")
		(10 "In4.Cu" signal "IN2")
		(12 "In5.Cu" signal "GND2")
		(14 "In6.Cu" signal "IN3")
		(16 "In7.Cu" signal "GND3")
		(18 "In8.Cu" signal "VCC")
		(20 "In9.Cu" signal "VCC1")
		(22 "In10.Cu" signal "GND4")
		(24 "In11.Cu" signal "IN4")
		(26 "In12.Cu" signal "GND5")
		(28 "In13.Cu" signal "IN5")
		(30 "In14.Cu" signal "GND6")
		(32 "In15.Cu" signal "IN6")
		(34 "In16.Cu" signal "GND7")
		(2 "B.Cu" signal "BOTTOM")
		(9 "F.Adhes" user "F.Adhesive")
		(11 "B.Adhes" user "B.Adhesive")
		(13 "F.Paste" user "Package Geometry/Pastemask Top")
		(15 "B.Paste" user "Package Geometry/Pastemask Bottom")
		(5 "F.SilkS" user "Ref Des/Silkscreen Top")
		(7 "B.SilkS" user "Ref Des/Silkscreen Bottom")
		(1 "F.Mask" user "Board Geometry/Soldermask Top")
		(3 "B.Mask" user "Board Geometry/Soldermask Bottom")
		(17 "Dwgs.User" user "User.Drawings")
		(19 "Cmts.User" user "User.Comments")
		(21 "Eco1.User" user "User.Eco1")
		(23 "Eco2.User" user "User.Eco2")
		(25 "Edge.Cuts" user "Board Geometry/Outline")
		(27 "Margin" user)
		(31 "F.CrtYd" user "Package Geometry/Place Bound Top")
		(29 "B.CrtYd" user "Package Geometry/Place Bound Bottom")
		(35 "F.Fab" user "Ref Des/Assembly Top")
		(33 "B.Fab" user "Ref Des/Assembly Bottom")
	)
	(footprint ""
		(layer "F.Cu")
		(at 315.110622 -50.155348)
		(property "Reference" "R3040"
			(at 0 0 0)
			(layer "F.SilkS")
			(hide yes)
			(effects
				(font
					(size 1.27 1.27)
				)
			)
		)
		(property "Value" ""
			(at 0 0 0)
			(layer "F.Fab")
			(effects
				(font
					(size 1.27 1.27)
				)
			)
		)
		(duplicate_pad_numbers_are_jumpers no)
		(fp_line
			(start -0.7874 -0.4064)
			(end 0.7874 -0.4064)
			(stroke
				(width 0.1524)
				(type default)
			)
			(layer "F.SilkS")
		)
		(fp_line
			(start -0.7874 0.4064)
			(end -0.7874 -0.4064)
			(stroke
				(width 0.1524)
				(type default)
			)
			(layer "F.SilkS")
		)
		(fp_line
			(start 0.7874 -0.4064)
			(end 0.7874 0.4064)
			(stroke
				(width 0.1524)
				(type default)
			)
			(layer "F.SilkS")
		)
		(fp_line
			(start 0.7874 0.4064)
			(end -0.7874 0.4064)
			(stroke
				(width 0.1524)
				(type default)
			)
			(layer "F.SilkS")
		)
		(fp_line
			(start -0.67945 -0.305054)
			(end -0.12065 -0.305054)
			(stroke
				(width 0.1)
				(type default)
			)
			(layer "F.Fab")
		)
		(fp_line
			(start -0.67945 0.3048)
			(end -0.67945 -0.305054)
			(stroke
				(width 0.1)
				(type default)
			)
			(layer "F.Fab")
		)
		(fp_line
			(start -0.12065 -0.305054)
			(end -0.12065 -0.2794)
			(stroke
				(width 0.1)
				(type default)
			)
			(layer "F.Fab")
		)
		(fp_line
			(start -0.12065 -0.2794)
			(end 0.12065 -0.2794)
			(stroke
				(width 0.1)
				(type default)
			)
			(layer "F.Fab")
		)
		(fp_line
			(start -0.12065 0.2794)
			(end -0.12065 0.3048)
			(stroke
				(width 0.1)
				(type default)
			)
			(layer "F.Fab")
		)
		(fp_line
			(start -0.12065 0.3048)
			(end -0.67945 0.3048)
			(stroke
				(width 0.1)
				(type default)
			)
			(layer "F.Fab")
		)
		(fp_line
			(start 0.120396 0.2794)
			(end -0.12065 0.2794)
			(stroke
				(width 0.1)
				(type default)
			)
			(layer "F.Fab")
		)
		(fp_line
			(start 0.120396 0.3048)
			(end 0.120396 0.2794)
			(stroke
				(width 0.1)
				(type default)
			)
			(layer "F.Fab")
		)
		(fp_line
			(start 0.12065 -0.3048)
			(end 0.67945 -0.3048)
			(stroke
				(width 0.1)
				(type default)
			)
			(layer "F.Fab")
		)
		(fp_line
			(start 0.12065 -0.2794)
			(end 0.12065 -0.3048)
			(stroke
				(width 0.1)
				(type default)
			)
			(layer "F.Fab")
		)
		(fp_line
			(start 0.67945 -0.3048)
			(end 0.67945 0.3048)
			(stroke
				(width 0.1)
				(type default)
			)
			(layer "F.Fab")
		)
		(fp_line
			(start 0.67945 0.3048)
			(end 0.120396 0.3048)
			(stroke
				(width 0.1)
				(type default)
			)
			(layer "F.Fab")
		)
		(pad "1" smd circle
			(at -0.40005 0)
			(size 0 0)
			(layers "F.Cu" "F.Mask" "F.Paste")
			(net "P3V3_AUX")
		)
		(pad "2" smd circle
			(at 0.40005 0)
			(size 0 0)
			(layers "F.Cu" "F.Mask" "F.Paste")
			(net "IRQ_PCH_SCI_WHEA_N")
		)
	)
	(footprint ""
		(layer "F.Cu")
		(at 427.452028 -172.453808)
		(property "Reference" "PC207"
			(at 0 0 0)
			(layer "F.SilkS")
			(hide yes)
			(effects
				(font
					(size 1.27 1.27)
				)
			)
		)
		(property "Value" ""
			(at 0 0 0)
			(layer "F.Fab")
			(effects
				(font
					(size 1.27 1.27)
				)
			)
		)
		(duplicate_pad_numbers_are_jumpers no)
		(fp_line
			(start -3.400044 1.249934)
			(end 3.400044 1.249934)
			(stroke
				(width 0.1524)
				(type default)
			)
			(layer "F.SilkS")
		)
		(fp_circle
			(center 0 1.249934)
			(end 3.400044 1.249934)
			(stroke
				(width 0.1524)
				(type default)
			)
			(fill no)
			(layer "F.SilkS")
		)
		(fp_poly
			(pts
				(arc
					(start -3.400044 1.249934)
					(mid 0 4.649978)
					(end 3.400044 1.249934)
				)
			)
			(stroke
				(width 0)
				(type default)
			)
			(fill yes)
			(layer "F.SilkS")
		)
		(fp_circle
			(center 0 1.249934)
			(end 3.400044 1.249934)
			(stroke
				(width 0.1)
				(type default)
			)
			(fill no)
			(layer "F.Fab")
		)
		(pad "1" thru_hole rect
			(at 0 0)
			(size 1.524 1.524)
			(drill 1.016)
			(layers "*.Cu" "*.Mask")
			(remove_unused_layers no)
			(net "SW_P12V_PVCCINFAON_CPU0_FLT")
			(clearance 0)
			(padstack
				(mode front_inner_back)
				(layer "Inner"
					(shape circle)
					(size 1.524 1.524)
					(clearance 0)
				)
				(layer "B.Cu"
					(shape rect)
					(size 1.524 1.524)
					(clearance 0)
				)
			)
		)
		(pad "2" thru_hole circle
			(at 0 2.500122)
			(size 1.524 1.524)
			(drill 1.016)
			(layers "*.Cu" "*.Mask")
			(remove_unused_layers no)
			(net "GND")
			(clearance 0)
		)
	)
	(footprint ""
		(layer "F.Cu")
		(at 420.682166 -138.333988)
		(property "Reference" "R2392"
			(at 0 0 0)
			(layer "F.SilkS")
			(hide yes)
			(effects
				(font
					(size 1.27 1.27)
				)
			)
		)
		(property "Value" ""
			(at 0 0 0)
			(layer "F.Fab")
			(effects
				(font
					(size 1.27 1.27)
				)
			)
		)
		(duplicate_pad_numbers_are_jumpers no)
		(fp_line
			(start -0.7874 -0.4064)
			(end 0.7874 -0.4064)
			(stroke
				(width 0.1524)
				(type default)
			)
			(layer "F.SilkS")
		)
		(fp_line
			(start -0.7874 0.4064)
			(end -0.7874 -0.4064)
			(stroke
				(width 0.1524)
				(type default)
			)
			(layer "F.SilkS")
		)
		(fp_line
			(start 0.7874 -0.4064)
			(end 0.7874 0.4064)
			(stroke
				(width 0.1524)
				(type default)
			)
			(layer "F.SilkS")
		)
		(fp_line
			(start 0.7874 0.4064)
			(end -0.7874 0.4064)
			(stroke
				(width 0.1524)
				(type default)
			)
			(layer "F.SilkS")
		)
		(fp_line
			(start -0.67945 -0.305054)
			(end -0.12065 -0.305054)
			(stroke
				(width 0.1)
				(type default)
			)
			(layer "F.Fab")
		)
		(fp_line
			(start -0.67945 0.3048)
			(end -0.67945 -0.305054)
			(stroke
				(width 0.1)
				(type default)
			)
			(layer "F.Fab")
		)
		(fp_line
			(start -0.12065 -0.305054)
			(end -0.12065 -0.2794)
			(stroke
				(width 0.1)
				(type default)
			)
			(layer "F.Fab")
		)
		(fp_line
			(start -0.12065 -0.2794)
			(end 0.12065 -0.2794)
			(stroke
				(width 0.1)
				(type default)
			)
			(layer "F.Fab")
		)
		(fp_line
			(start -0.12065 0.2794)
			(end -0.12065 0.3048)
			(stroke
				(width 0.1)
				(type default)
			)
			(layer "F.Fab")
		)
		(fp_line
			(start -0.12065 0.3048)
			(end -0.67945 0.3048)
			(stroke
				(width 0.1)
				(type default)
			)
			(layer "F.Fab")
		)
		(fp_line
			(start 0.120396 0.2794)
			(end -0.12065 0.2794)
			(stroke
				(width 0.1)
				(type default)
			)
			(layer "F.Fab")
		)
		(fp_line
			(start 0.120396 0.3048)
			(end 0.120396 0.2794)
			(stroke
				(width 0.1)
				(type default)
			)
			(layer "F.Fab")
		)
		(fp_line
			(start 0.12065 -0.3048)
			(end 0.67945 -0.3048)
			(stroke
				(width 0.1)
				(type default)
			)
			(layer "F.Fab")
		)
		(fp_line
			(start 0.12065 -0.2794)
			(end 0.12065 -0.3048)
			(stroke
				(width 0.1)
				(type default)
			)
			(layer "F.Fab")
		)
		(fp_line
			(start 0.67945 -0.3048)
			(end 0.67945 0.3048)
			(stroke
				(width 0.1)
				(type default)
			)
			(layer "F.Fab")
		)
		(fp_line
			(start 0.67945 0.3048)
			(end 0.120396 0.3048)
			(stroke
				(width 0.1)
				(type default)
			)
			(layer "F.Fab")
		)
		(pad "1" smd circle
			(at -0.40005 0)
			(size 0 0)
			(layers "F.Cu" "F.Mask" "F.Paste")
			(net "P3V3_AUX")
		)
		(pad "2" smd circle
			(at 0.40005 0)
			(size 0 0)
			(layers "F.Cu" "F.Mask" "F.Paste")
			(net "PVCCINFAON_CPU0_VR_FAULT")
		)
	)
	(footprint ""
		(layer "F.Cu")
		(at 55.090314 -161.539174)
		(property "Reference" "PC2951"
			(at 0 0 0)
			(layer "F.SilkS")
			(hide yes)
			(effects
				(font
					(size 1.27 1.27)
				)
			)
		)
		(property "Value" ""
			(at 0 0 0)
			(layer "F.Fab")
			(effects
				(font
					(size 1.27 1.27)
				)
			)
		)
		(duplicate_pad_numbers_are_jumpers no)
		(fp_line
			(start -0.7874 -0.4064)
			(end 0.7874 -0.4064)
			(stroke
				(width 0.1524)
				(type default)
			)
			(layer "F.SilkS")
		)
		(fp_line
			(start -0.7874 0.4064)
			(end -0.7874 -0.4064)
			(stroke
				(width 0.1524)
				(type default)
			)
			(layer "F.SilkS")
		)
		(fp_line
			(start 0.7874 -0.4064)
			(end 0.7874 0.4064)
			(stroke
				(width 0.1524)
				(type default)
			)
			(layer "F.SilkS")
		)
		(fp_line
			(start 0.7874 0.4064)
			(end -0.7874 0.4064)
			(stroke
				(width 0.1524)
				(type default)
			)
			(layer "F.SilkS")
		)
		(fp_line
			(start -0.67945 -0.305054)
			(end -0.12065 -0.305054)
			(stroke
				(width 0.1)
				(type default)
			)
			(layer "F.Fab")
		)
		(fp_line
			(start -0.67945 0.3048)
			(end -0.67945 -0.305054)
			(stroke
				(width 0.1)
				(type default)
			)
			(layer "F.Fab")
		)
		(fp_line
			(start -0.12065 -0.305054)
			(end -0.12065 -0.2794)
			(stroke
				(width 0.1)
				(type default)
			)
			(layer "F.Fab")
		)
		(fp_line
			(start -0.12065 -0.2794)
			(end 0.12065 -0.2794)
			(stroke
				(width 0.1)
				(type default)
			)
			(layer "F.Fab")
		)
		(fp_line
			(start -0.12065 0.2794)
			(end -0.12065 0.3048)
			(stroke
				(width 0.1)
				(type default)
			)
			(layer "F.Fab")
		)
		(fp_line
			(start -0.12065 0.3048)
			(end -0.67945 0.3048)
			(stroke
				(width 0.1)
				(type default)
			)
			(layer "F.Fab")
		)
		(fp_line
			(start 0.120396 0.2794)
			(end -0.12065 0.2794)
			(stroke
				(width 0.1)
				(type default)
			)
			(layer "F.Fab")
		)
		(fp_line
			(start 0.120396 0.3048)
			(end 0.120396 0.2794)
			(stroke
				(width 0.1)
				(type default)
			)
			(layer "F.Fab")
		)
		(fp_line
			(start 0.12065 -0.3048)
			(end 0.67945 -0.3048)
			(stroke
				(width 0.1)
				(type default)
			)
			(layer "F.Fab")
		)
		(fp_line
			(start 0.12065 -0.2794)
			(end 0.12065 -0.3048)
			(stroke
				(width 0.1)
				(type default)
			)
			(layer "F.Fab")
		)
		(fp_line
			(start 0.67945 -0.3048)
			(end 0.67945 0.3048)
			(stroke
				(width 0.1)
				(type default)
			)
			(layer "F.Fab")
		)
		(fp_line
			(start 0.67945 0.3048)
			(end 0.120396 0.3048)
			(stroke
				(width 0.1)
				(type default)
			)
			(layer "F.Fab")
		)
		(pad "1" smd circle
			(at -0.40005 0)
			(size 0 0)
			(layers "F.Cu" "F.Mask" "F.Paste")
			(net "PVCCFA_EHV_CPU1_PVCC")
		)
		(pad "2" smd circle
			(at 0.40005 0)
			(size 0 0)
			(layers "F.Cu" "F.Mask" "F.Paste")
			(net "GND")
		)
	)
	(footprint ""
		(layer "F.Cu")
		(at 116.561616 -256.6543 -90)
		(property "Reference" "C289"
			(at 0 0 270)
			(layer "F.SilkS")
			(hide yes)
			(effects
				(font
					(size 1.27 1.27)
				)
			)
		)
		(property "Value" ""
			(at 0 0 270)
			(layer "F.Fab")
			(effects
				(font
					(size 1.27 1.27)
				)
			)
		)
		(duplicate_pad_numbers_are_jumpers no)
		(fp_line
			(start -0.7874 0.4064)
			(end -0.7874 -0.4064)
			(stroke
				(width 0.1524)
				(type default)
			)
			(layer "F.SilkS")
		)
		(fp_line
			(start 0.7874 0.4064)
			(end -0.7874 0.4064)
			(stroke
				(width 0.1524)
				(type default)
			)
			(layer "F.SilkS")
		)
		(fp_line
			(start -0.7874 -0.4064)
			(end 0.7874 -0.4064)
			(stroke
				(width 0.1524)
				(type default)
			)
			(layer "F.SilkS")
		)
		(fp_line
			(start 0.7874 -0.4064)
			(end 0.7874 0.4064)
			(stroke
				(width 0.1524)
				(type default)
			)
			(layer "F.SilkS")
		)
		(fp_line
			(start -0.67945 0.3048)
			(end -0.67945 -0.305054)
			(stroke
				(width 0.1)
				(type default)
			)
			(layer "F.Fab")
		)
		(fp_line
			(start -0.12065 0.3048)
			(end -0.67945 0.3048)
			(stroke
				(width 0.1)
				(type default)
			)
			(layer "F.Fab")
		)
		(fp_line
			(start 0.120396 0.3048)
			(end 0.120396 0.2794)
			(stroke
				(width 0.1)
				(type default)
			)
			(layer "F.Fab")
		)
		(fp_line
			(start 0.67945 0.3048)
			(end 0.120396 0.3048)
			(stroke
				(width 0.1)
				(type default)
			)
			(layer "F.Fab")
		)
		(fp_line
			(start -0.12065 0.2794)
			(end -0.12065 0.3048)
			(stroke
				(width 0.1)
				(type default)
			)
			(layer "F.Fab")
		)
		(fp_line
			(start 0.120396 0.2794)
			(end -0.12065 0.2794)
			(stroke
				(width 0.1)
				(type default)
			)
			(layer "F.Fab")
		)
		(fp_line
			(start -0.12065 -0.2794)
			(end 0.12065 -0.2794)
			(stroke
				(width 0.1)
				(type default)
			)
			(layer "F.Fab")
		)
		(fp_line
			(start 0.12065 -0.2794)
			(end 0.12065 -0.3048)
			(stroke
				(width 0.1)
				(type default)
			)
			(layer "F.Fab")
		)
		(fp_line
			(start 0.12065 -0.3048)
			(end 0.67945 -0.3048)
			(stroke
				(width 0.1)
				(type default)
			)
			(layer "F.Fab")
		)
		(fp_line
			(start 0.67945 -0.3048)
			(end 0.67945 0.3048)
			(stroke
				(width 0.1)
				(type default)
			)
			(layer "F.Fab")
		)
		(fp_line
			(start -0.67945 -0.305054)
			(end -0.12065 -0.305054)
			(stroke
				(width 0.1)
				(type default)
			)
			(layer "F.Fab")
		)
		(fp_line
			(start -0.12065 -0.305054)
			(end -0.12065 -0.2794)
			(stroke
				(width 0.1)
				(type default)
			)
			(layer "F.Fab")
		)
		(pad "1" smd circle
			(at -0.40005 0 270)
			(size 0 0)
			(layers "F.Cu" "F.Mask" "F.Paste")
			(net "PVCCIN_CPU1")
		)
		(pad "2" smd circle
			(at 0.40005 0 270)
			(size 0 0)
			(layers "F.Cu" "F.Mask" "F.Paste")
			(net "GND")
		)
	)
	(footprint ""
		(layer "F.Cu")
		(at 175.4124 -94.338648 90)
		(property "Reference" "R4583"
			(at 0 0 90)
			(layer "F.SilkS")
			(hide yes)
			(effects
				(font
					(size 1.27 1.27)
				)
			)
		)
		(property "Value" ""
			(at 0 0 90)
			(layer "F.Fab")
			(effects
				(font
					(size 1.27 1.27)
				)
			)
		)
		(duplicate_pad_numbers_are_jumpers no)
		(fp_line
			(start 0.7874 -0.4064)
			(end 0.7874 0.4064)
			(stroke
				(width 0.1524)
				(type default)
			)
			(layer "F.SilkS")
		)
		(fp_line
			(start -0.7874 -0.4064)
			(end 0.7874 -0.4064)
			(stroke
				(width 0.1524)
				(type default)
			)
			(layer "F.SilkS")
		)
		(fp_line
			(start 0.7874 0.4064)
			(end -0.7874 0.4064)
			(stroke
				(width 0.1524)
				(type default)
			)
			(layer "F.SilkS")
		)
		(fp_line
			(start -0.7874 0.4064)
			(end -0.7874 -0.4064)
			(stroke
				(width 0.1524)
				(type default)
			)
			(layer "F.SilkS")
		)
		(fp_line
			(start -0.12065 -0.305054)
			(end -0.12065 -0.2794)
			(stroke
				(width 0.1)
				(type default)
			)
			(layer "F.Fab")
		)
		(fp_line
			(start -0.67945 -0.305054)
			(end -0.12065 -0.305054)
			(stroke
				(width 0.1)
				(type default)
			)
			(layer "F.Fab")
		)
		(fp_line
			(start 0.67945 -0.3048)
			(end 0.67945 0.3048)
			(stroke
				(width 0.1)
				(type default)
			)
			(layer "F.Fab")
		)
		(fp_line
			(start 0.12065 -0.3048)
			(end 0.67945 -0.3048)
			(stroke
				(width 0.1)
				(type default)
			)
			(layer "F.Fab")
		)
		(fp_line
			(start 0.12065 -0.2794)
			(end 0.12065 -0.3048)
			(stroke
				(width 0.1)
				(type default)
			)
			(layer "F.Fab")
		)
		(fp_line
			(start -0.12065 -0.2794)
			(end 0.12065 -0.2794)
			(stroke
				(width 0.1)
				(type default)
			)
			(layer "F.Fab")
		)
		(fp_line
			(start 0.120396 0.2794)
			(end -0.12065 0.2794)
			(stroke
				(width 0.1)
				(type default)
			)
			(layer "F.Fab")
		)
		(fp_line
			(start -0.12065 0.2794)
			(end -0.12065 0.3048)
			(stroke
				(width 0.1)
				(type default)
			)
			(layer "F.Fab")
		)
		(fp_line
			(start 0.67945 0.3048)
			(end 0.120396 0.3048)
			(stroke
				(width 0.1)
				(type default)
			)
			(layer "F.Fab")
		)
		(fp_line
			(start 0.120396 0.3048)
			(end 0.120396 0.2794)
			(stroke
				(width 0.1)
				(type default)
			)
			(layer "F.Fab")
		)
		(fp_line
			(start -0.12065 0.3048)
			(end -0.67945 0.3048)
			(stroke
				(width 0.1)
				(type default)
			)
			(layer "F.Fab")
		)
		(fp_line
			(start -0.67945 0.3048)
			(end -0.67945 -0.305054)
			(stroke
				(width 0.1)
				(type default)
			)
			(layer "F.Fab")
		)
		(pad "1" smd rect
			(at -0.40005 0 270)
			(size 0.4572 0.508)
			(layers "F.Cu" "F.Mask" "F.Paste")
			(net "FM_BOARD_BMC_SKU_ID1")
		)
		(pad "2" smd rect
			(at 0.40005 0 270)
			(size 0.4572 0.508)
			(layers "F.Cu" "F.Mask" "F.Paste")
			(net "GND")
		)
	)
)
